# S9S_MB_2U (Grand Teton) — schematic netlist excerpt (pin names and nets, part order shuffled) for the footprints in the layout excerpt that follows; sources: Cadence DE-HDL packaged netlist, KiCad conversion of 03242023_DA0F0TMBIJ0_F0T_Motherboard_J_brd_V01_OCP.brd

PL34  Q_INDUCTOR  130NH/106A IND  pkg SMLF  page 271 : \1\ = SW_PVCCFA_EHV_FIVRA_CPU0_SW2 ; \2\ = PVCCFA_EHV_FIVRA_CPU0
C1170  Q_CAP  10UF 16V 10% X6S  pkg C0805  page 260 : A = P5V_AUX ; B = GND
C1291  Q_CAP  1UF 25V 10% X6S  pkg C0402  page 239 : A = P3V3_AUX ; B = GND

(kicad_pcb
	(version 20260206)
	(generator "pcbnew")
	(generator_version "10.0")
	(general
		(thickness 1.6)
		(legacy_teardrops no)
	)
	(paper "A4")
	(title_block
		(title "03242023_DA0F0TMBIJ0_F0T_Motherboard_J_brd_V01_OCP.brd")
		(comment 1 "Grand Teton / footprints 153-155 of 6105")
	)
	(layers
		(0 "F.Cu" signal "TOP")
		(4 "In1.Cu" signal "GND")
		(6 "In2.Cu" signal "IN1")
		(8 "In3.Cu" signal "GND1")
		(10 "In4.Cu" signal "IN2")
		(12 "In5.Cu" signal "GND2")
		(14 "In6.Cu" signal "IN3")
		(16 "In7.Cu" signal "GND3")
		(18 "In8.Cu" signal "VCC")
		(20 "In9.Cu" signal "VCC1")
		(22 "In10.Cu" signal "GND4")
		(24 "In11.Cu" signal "IN4")
		(26 "In12.Cu" signal "GND5")
		(28 "In13.Cu" signal "IN5")
		(30 "In14.Cu" signal "GND6")
		(32 "In15.Cu" signal "IN6")
		(34 "In16.Cu" signal "GND7")
		(2 "B.Cu" signal "BOTTOM")
		(9 "F.Adhes" user "F.Adhesive")
		(11 "B.Adhes" user "B.Adhesive")
		(13 "F.Paste" user "Package Geometry/Pastemask Top")
		(15 "B.Paste" user "Package Geometry/Pastemask Bottom")
		(5 "F.SilkS" user "Ref Des/Silkscreen Top")
		(7 "B.SilkS" user "Ref Des/Silkscreen Bottom")
		(1 "F.Mask" user "Board Geometry/Soldermask Top")
		(3 "B.Mask" user "Board Geometry/Soldermask Bottom")
		(17 "Dwgs.User" user "User.Drawings")
		(19 "Cmts.User" user "User.Comments")
		(21 "Eco1.User" user "User.Eco1")
		(23 "Eco2.User" user "User.Eco2")
		(25 "Edge.Cuts" user "Board Geometry/Outline")
		(27 "Margin" user)
		(31 "F.CrtYd" user "Package Geometry/Place Bound Top")
		(29 "B.CrtYd" user "Package Geometry/Place Bound Bottom")
		(35 "F.Fab" user "Ref Des/Assembly Top")
		(33 "B.Fab" user "Ref Des/Assembly Bottom")
	)
	(footprint ""
		(layer "F.Cu")
		(at 368.75212 -103.866188 90)
		(property "Reference" "C1291"
			(at 0 0 90)
			(layer "F.SilkS")
			(hide yes)
			(effects
				(font
					(size 1.27 1.27)
				)
			)
		)
		(property "Value" ""
			(at 0 0 90)
			(layer "F.Fab")
			(effects
				(font
					(size 1.27 1.27)
				)
			)
		)
		(duplicate_pad_numbers_are_jumpers no)
		(fp_line
			(start 0.7874 -0.4064)
			(end 0.7874 0.4064)
			(stroke
				(width 0.1524)
				(type default)
			)
			(layer "F.SilkS")
		)
		(fp_line
			(start -0.7874 -0.4064)
			(end 0.7874 -0.4064)
			(stroke
				(width 0.1524)
				(type default)
			)
			(layer "F.SilkS")
		)
		(fp_line
			(start 0.7874 0.4064)
			(end -0.7874 0.4064)
			(stroke
				(width 0.1524)
				(type default)
			)
			(layer "F.SilkS")
		)
		(fp_line
			(start -0.7874 0.4064)
			(end -0.7874 -0.4064)
			(stroke
				(width 0.1524)
				(type default)
			)
			(layer "F.SilkS")
		)
		(fp_line
			(start -0.12065 -0.305054)
			(end -0.12065 -0.2794)
			(stroke
				(width 0.1)
				(type default)
			)
			(layer "F.Fab")
		)
		(fp_line
			(start -0.67945 -0.305054)
			(end -0.12065 -0.305054)
			(stroke
				(width 0.1)
				(type default)
			)
			(layer "F.Fab")
		)
		(fp_line
			(start 0.67945 -0.3048)
			(end 0.67945 0.3048)
			(stroke
				(width 0.1)
				(type default)
			)
			(layer "F.Fab")
		)
		(fp_line
			(start 0.12065 -0.3048)
			(end 0.67945 -0.3048)
			(stroke
				(width 0.1)
				(type default)
			)
			(layer "F.Fab")
		)
		(fp_line
			(start 0.12065 -0.2794)
			(end 0.12065 -0.3048)
			(stroke
				(width 0.1)
				(type default)
			)
			(layer "F.Fab")
		)
		(fp_line
			(start -0.12065 -0.2794)
			(end 0.12065 -0.2794)
			(stroke
				(width 0.1)
				(type default)
			)
			(layer "F.Fab")
		)
		(fp_line
			(start 0.120396 0.2794)
			(end -0.12065 0.2794)
			(stroke
				(width 0.1)
				(type default)
			)
			(layer "F.Fab")
		)
		(fp_line
			(start -0.12065 0.2794)
			(end -0.12065 0.3048)
			(stroke
				(width 0.1)
				(type default)
			)
			(layer "F.Fab")
		)
		(fp_line
			(start 0.67945 0.3048)
			(end 0.120396 0.3048)
			(stroke
				(width 0.1)
				(type default)
			)
			(layer "F.Fab")
		)
		(fp_line
			(start 0.120396 0.3048)
			(end 0.120396 0.2794)
			(stroke
				(width 0.1)
				(type default)
			)
			(layer "F.Fab")
		)
		(fp_line
			(start -0.12065 0.3048)
			(end -0.67945 0.3048)
			(stroke
				(width 0.1)
				(type default)
			)
			(layer "F.Fab")
		)
		(fp_line
			(start -0.67945 0.3048)
			(end -0.67945 -0.305054)
			(stroke
				(width 0.1)
				(type default)
			)
			(layer "F.Fab")
		)
		(pad "1" smd circle
			(at -0.40005 0 90)
			(size 0 0)
			(layers "F.Cu" "F.Mask" "F.Paste")
			(net "P3V3_AUX")
		)
		(pad "2" smd circle
			(at 0.40005 0 90)
			(size 0 0)
			(layers "F.Cu" "F.Mask" "F.Paste")
			(net "GND")
		)
	)
	(footprint ""
		(layer "F.Cu")
		(at 446.18783 -378.300234)
		(property "Reference" "C1170"
			(at 0 0 0)
			(layer "F.SilkS")
			(hide yes)
			(effects
				(font
					(size 1.27 1.27)
				)
			)
		)
		(property "Value" ""
			(at 0 0 0)
			(layer "F.Fab")
			(effects
				(font
					(size 1.27 1.27)
				)
			)
		)
		(duplicate_pad_numbers_are_jumpers no)
		(fp_line
			(start -1.524 -0.762)
			(end 1.524 -0.762)
			(stroke
				(width 0.1524)
				(type default)
			)
			(layer "F.SilkS")
		)
		(fp_line
			(start -1.524 0.762)
			(end -1.524 -0.762)
			(stroke
				(width 0.1524)
				(type default)
			)
			(layer "F.SilkS")
		)
		(fp_line
			(start 1.524 -0.762)
			(end 1.524 0.762)
			(stroke
				(width 0.1524)
				(type default)
			)
			(layer "F.SilkS")
		)
		(fp_line
			(start 1.524 0.762)
			(end -1.524 0.762)
			(stroke
				(width 0.1524)
				(type default)
			)
			(layer "F.SilkS")
		)
		(fp_line
			(start -1.1049 -0.724916)
			(end -1.1049 0.724916)
			(stroke
				(width 0.1)
				(type default)
			)
			(layer "F.Fab")
		)
		(fp_line
			(start -1.1049 0.724916)
			(end 1.1049 0.724916)
			(stroke
				(width 0.1)
				(type default)
			)
			(layer "F.Fab")
		)
		(fp_line
			(start 1.1049 -0.724916)
			(end -1.1049 -0.724916)
			(stroke
				(width 0.1)
				(type default)
			)
			(layer "F.Fab")
		)
		(fp_line
			(start 1.1049 0.724916)
			(end 1.1049 -0.724916)
			(stroke
				(width 0.1)
				(type default)
			)
			(layer "F.Fab")
		)
		(pad "1" smd rect
			(at -0.889 0 180)
			(size 1.016 1.27)
			(layers "F.Cu" "F.Mask" "F.Paste")
			(net "P5V_AUX")
		)
		(pad "2" smd rect
			(at 0.889 0 180)
			(size 1.016 1.27)
			(layers "F.Cu" "F.Mask" "F.Paste")
			(net "GND")
		)
	)
	(footprint ""
		(layer "F.Cu")
		(at 298.472352 -354.000816 -90)
		(property "Reference" "PL34"
			(at -2.045462 -5.057648 0)
			(unlocked yes)
			(layer "F.SilkS")
			(effects
				(font
					(size 0.7874 0.5842)
					(thickness 0.1524)
				)
				(justify left)
			)
		)
		(property "Value" ""
			(at 0 0 270)
			(layer "F.Fab")
			(effects
				(font
					(size 1.27 1.27)
				)
			)
		)
		(duplicate_pad_numbers_are_jumpers no)
		(fp_line
			(start -4.99999 3.750056)
			(end -4.99999 2.2479)
			(stroke
				(width 0.1524)
				(type default)
			)
			(layer "F.SilkS")
		)
		(fp_line
			(start 0 3.750056)
			(end -4.99999 3.750056)
			(stroke
				(width 0.1524)
				(type default)
			)
			(layer "F.SilkS")
		)
		(fp_line
			(start 4.99999 3.750056)
			(end 0 3.750056)
			(stroke
				(width 0.1524)
				(type default)
			)
			(layer "F.SilkS")
		)
		(fp_line
			(start 4.99999 2.2352)
			(end 4.99999 3.750056)
			(stroke
				(width 0.1524)
				(type default)
			)
			(layer "F.SilkS")
		)
		(fp_line
			(start -4.99999 -2.2479)
			(end -4.99999 -3.750056)
			(stroke
				(width 0.1524)
				(type default)
			)
			(layer "F.SilkS")
		)
		(fp_line
			(start -4.99999 -3.750056)
			(end 4.99999 -3.750056)
			(stroke
				(width 0.1524)
				(type default)
			)
			(layer "F.SilkS")
		)
		(fp_line
			(start 4.99999 -3.750056)
			(end 4.99999 -2.2479)
			(stroke
				(width 0.1524)
				(type default)
			)
			(layer "F.SilkS")
		)
		(fp_line
			(start -4.99999 3.750056)
			(end -4.99999 -3.750056)
			(stroke
				(width 0.1)
				(type default)
			)
			(layer "F.Fab")
		)
		(fp_line
			(start 0 3.750056)
			(end -4.99999 3.750056)
			(stroke
				(width 0.1)
				(type default)
			)
			(layer "F.Fab")
		)
		(fp_line
			(start 4.99999 3.750056)
			(end 0 3.750056)
			(stroke
				(width 0.1)
				(type default)
			)
			(layer "F.Fab")
		)
		(fp_line
			(start -4.99999 -3.750056)
			(end 4.99999 -3.750056)
			(stroke
				(width 0.1)
				(type default)
			)
			(layer "F.Fab")
		)
		(fp_line
			(start 4.99999 -3.750056)
			(end 4.99999 3.750056)
			(stroke
				(width 0.1)
				(type default)
			)
			(layer "F.Fab")
		)
		(pad "1" smd rect
			(at -3.299968 0 270)
			(size 3.302 4.2164)
			(layers "F.Cu" "F.Mask" "F.Paste")
			(net "SW_PVCCFA_EHV_FIVRA_CPU0_SW2")
		)
		(pad "2" smd rect
			(at 3.299968 0 270)
			(size 3.302 4.2164)
			(layers "F.Cu" "F.Mask" "F.Paste")
			(net "PVCCFA_EHV_FIVRA_CPU0")
		)
	)
)
